(kicad_pcb
	(version 20260206)
	(generator "pcbnew")
	(generator_version "10.0")
	(general
		(thickness 1.6)
		(legacy_teardrops no)
	)
	(paper "A4")
	(title_block
		(title "baseboard — 13948-1b.1110WZS1818.brd")
		(comment 1 "Honey Badger (Wiwynn) / footprints 1878-1885 of 2523")
	)
	(layers
		(0 "F.Cu" signal "TOP")
		(4 "In1.Cu" signal "L2GND")
		(6 "In2.Cu" signal "L3")
		(8 "In3.Cu" signal "L4VCC")
		(10 "In4.Cu" signal "L5VCC")
		(12 "In5.Cu" signal "L6")
		(14 "In6.Cu" signal "L7GND")
		(2 "B.Cu" signal "BOTTOM")
		(9 "F.Adhes" user "F.Adhesive")
		(11 "B.Adhes" user "B.Adhesive")
		(13 "F.Paste" user "Package Geometry/Pastemask Top")
		(15 "B.Paste" user "Package Geometry/Pastemask Bottom")
		(5 "F.SilkS" user "Ref Des/Silkscreen Top")
		(7 "B.SilkS" user "Ref Des/Silkscreen Bottom")
		(1 "F.Mask" user "Board Geometry/Soldermask Top")
		(3 "B.Mask" user "Board Geometry/Soldermask Bottom")
		(17 "Dwgs.User" user "User.Drawings")
		(19 "Cmts.User" user "User.Comments")
		(21 "Eco1.User" user "User.Eco1")
		(23 "Eco2.User" user "User.Eco2")
		(25 "Edge.Cuts" user "Board Geometry/Outline")
		(27 "Margin" user)
		(31 "F.CrtYd" user "Package Geometry/Place Bound Top")
		(29 "B.CrtYd" user "Package Geometry/Place Bound Bottom")
		(35 "F.Fab" user "Ref Des/Assembly Top")
		(33 "B.Fab" user "Ref Des/Assembly Bottom")
	)
	(footprint ""
		(layer "B.Cu")
		(at 274.193 -175.641 90)
		(property "Reference" "R364"
			(at 0 0 90)
			(layer "B.SilkS")
			(hide yes)
			(effects
				(font
					(size 1.27 1.27)
				)
				(justify mirror)
			)
		)
		(property "Value" "3K3R2F-2-GP"
			(at -0.064008 -3.993896 90)
			(unlocked yes)
			(layer "B.Fab")
			(hide yes)
			(effects
				(font
					(size 1.016 1.016)
					(thickness 0.1524)
				)
				(justify mirror)
			)
		)
		(property "Device Type" "R402H16"
			(at -0.064008 -5.517896 90)
			(unlocked yes)
			(layer "B.Fab")
			(hide yes)
			(effects
				(font
					(size 1.016 1.016)
					(thickness 0.1524)
				)
				(justify mirror)
			)
		)
		(duplicate_pad_numbers_are_jumpers no)
		(fp_line
			(start 0.508 -0.9398)
			(end 0.508 0.9398)
			(stroke
				(width 0.1524)
				(type default)
			)
			(layer "B.SilkS")
		)
		(fp_line
			(start -0.508 -0.9398)
			(end 0.508 -0.9398)
			(stroke
				(width 0.1524)
				(type default)
			)
			(layer "B.SilkS")
		)
		(fp_rect
			(start 0.508 0.9398)
			(end -0.508 -0.9398)
			(stroke
				(width 0)
				(type default)
			)
			(fill no)
			(layer "B.CrtYd")
		)
		(fp_rect
			(start 0.508 0.9398)
			(end -0.508 -0.9398)
			(stroke
				(width 0)
				(type default)
			)
			(fill no)
			(layer "B.Fab")
		)
		(pad "1" smd custom
			(at 0 -0.4445 270)
			(size 0.1397 0.1397)
			(layers "B.Cu" "B.Mask" "B.Paste")
			(net "P3V3_STBY")
			(options
				(clearance outline)
				(anchor circle)
			)
			(primitives
				(gr_poly
					(pts
						(arc
							(start -0.1778 0.2794)
							(mid -0.249642 0.249642)
							(end -0.2794 0.1778)
						)
						(arc
							(start -0.2794 -0.1778)
							(mid -0.249642 -0.249642)
							(end -0.1778 -0.2794)
						)
						(arc
							(start 0.1778 -0.2794)
							(mid 0.249642 -0.249642)
							(end 0.2794 -0.1778)
						)
						(arc
							(start 0.2794 0.1778)
							(mid 0.249642 0.249642)
							(end 0.1778 0.2794)
						)
					)
					(width 0)
					(fill yes)
				)
			)
		)
		(pad "2" smd custom
			(at 0 0.4445 270)
			(size 0.1397 0.1397)
			(layers "B.Cu" "B.Mask" "B.Paste")
			(net "ROMA14")
			(options
				(clearance outline)
				(anchor circle)
			)
			(primitives
				(gr_poly
					(pts
						(arc
							(start -0.1778 0.2794)
							(mid -0.249642 0.249642)
							(end -0.2794 0.1778)
						)
						(arc
							(start -0.2794 -0.1778)
							(mid -0.249642 -0.249642)
							(end -0.1778 -0.2794)
						)
						(arc
							(start 0.1778 -0.2794)
							(mid 0.249642 -0.249642)
							(end 0.2794 -0.1778)
						)
						(arc
							(start 0.2794 0.1778)
							(mid 0.249642 0.249642)
							(end 0.1778 0.2794)
						)
					)
					(width 0)
					(fill yes)
				)
			)
		)
	)
	(footprint ""
		(layer "B.Cu")
		(at 15.62608 -231.822752)
		(property "Reference" "R516"
			(at 0 0 0)
			(layer "B.SilkS")
			(hide yes)
			(effects
				(font
					(size 1.27 1.27)
				)
				(justify mirror)
			)
		)
		(property "Value" "0R2J-2-GP"
			(at -0.064008 -3.993896 0)
			(unlocked yes)
			(layer "B.Fab")
			(hide yes)
			(effects
				(font
					(size 1.016 1.016)
					(thickness 0.1524)
				)
				(justify mirror)
			)
		)
		(property "Device Type" "R402H16"
			(at -0.064008 -5.517896 0)
			(unlocked yes)
			(layer "B.Fab")
			(hide yes)
			(effects
				(font
					(size 1.016 1.016)
					(thickness 0.1524)
				)
				(justify mirror)
			)
		)
		(duplicate_pad_numbers_are_jumpers no)
		(fp_line
			(start -0.508 -0.9398)
			(end 0.508 -0.9398)
			(stroke
				(width 0.1524)
				(type default)
			)
			(layer "B.SilkS")
		)
		(fp_line
			(start 0.508 -0.9398)
			(end 0.508 0.9398)
			(stroke
				(width 0.1524)
				(type default)
			)
			(layer "B.SilkS")
		)
		(fp_rect
			(start 0.508 0.9398)
			(end -0.508 -0.9398)
			(stroke
				(width 0)
				(type default)
			)
			(fill no)
			(layer "B.CrtYd")
		)
		(fp_rect
			(start 0.508 0.9398)
			(end -0.508 -0.9398)
			(stroke
				(width 0)
				(type default)
			)
			(fill no)
			(layer "B.Fab")
		)
		(pad "1" smd custom
			(at 0 -0.4445 180)
			(size 0.1397 0.1397)
			(layers "B.Cu" "B.Mask" "B.Paste")
			(net "SAS_HDD_PWR14_PCIE")
			(options
				(clearance outline)
				(anchor circle)
			)
			(primitives
				(gr_poly
					(pts
						(arc
							(start -0.1778 0.2794)
							(mid -0.249642 0.249642)
							(end -0.2794 0.1778)
						)
						(arc
							(start -0.2794 -0.1778)
							(mid -0.249642 -0.249642)
							(end -0.1778 -0.2794)
						)
						(arc
							(start 0.1778 -0.2794)
							(mid 0.249642 -0.249642)
							(end 0.2794 -0.1778)
						)
						(arc
							(start 0.2794 0.1778)
							(mid 0.249642 0.249642)
							(end 0.1778 0.2794)
						)
					)
					(width 0)
					(fill yes)
				)
			)
		)
		(pad "2" smd custom
			(at 0 0.4445 180)
			(size 0.1397 0.1397)
			(layers "B.Cu" "B.Mask" "B.Paste")
			(net "SAS_HDD_PWR14")
			(options
				(clearance outline)
				(anchor circle)
			)
			(primitives
				(gr_poly
					(pts
						(arc
							(start -0.1778 0.2794)
							(mid -0.249642 0.249642)
							(end -0.2794 0.1778)
						)
						(arc
							(start -0.2794 -0.1778)
							(mid -0.249642 -0.249642)
							(end -0.1778 -0.2794)
						)
						(arc
							(start 0.1778 -0.2794)
							(mid 0.249642 -0.249642)
							(end 0.2794 -0.1778)
						)
						(arc
							(start 0.2794 0.1778)
							(mid 0.249642 0.249642)
							(end 0.1778 0.2794)
						)
					)
					(width 0)
					(fill yes)
				)
			)
		)
	)
	(footprint ""
		(layer "B.Cu")
		(at 102.87 -239.395)
		(property "Reference" "SR846"
			(at 0 0 0)
			(layer "B.SilkS")
			(hide yes)
			(effects
				(font
					(size 1.27 1.27)
				)
				(justify mirror)
			)
		)
		(property "Value" "4K7R2F-GP"
			(at -0.064008 -3.993896 0)
			(unlocked yes)
			(layer "B.Fab")
			(hide yes)
			(effects
				(font
					(size 1.016 1.016)
					(thickness 0.1524)
				)
				(justify mirror)
			)
		)
		(property "Device Type" "R402H16"
			(at -0.064008 -5.517896 0)
			(unlocked yes)
			(layer "B.Fab")
			(hide yes)
			(effects
				(font
					(size 1.016 1.016)
					(thickness 0.1524)
				)
				(justify mirror)
			)
		)
		(duplicate_pad_numbers_are_jumpers no)
		(fp_line
			(start -0.508 -0.9398)
			(end 0.508 -0.9398)
			(stroke
				(width 0.1524)
				(type default)
			)
			(layer "B.SilkS")
		)
		(fp_line
			(start 0.508 -0.9398)
			(end 0.508 0.9398)
			(stroke
				(width 0.1524)
				(type default)
			)
			(layer "B.SilkS")
		)
		(fp_rect
			(start 0.508 0.9398)
			(end -0.508 -0.9398)
			(stroke
				(width 0)
				(type default)
			)
			(fill no)
			(layer "B.CrtYd")
		)
		(fp_rect
			(start 0.508 0.9398)
			(end -0.508 -0.9398)
			(stroke
				(width 0)
				(type default)
			)
			(fill no)
			(layer "B.Fab")
		)
		(pad "1" smd custom
			(at 0 -0.4445 180)
			(size 0.1397 0.1397)
			(layers "B.Cu" "B.Mask" "B.Paste")
			(net "SAS_FAULT_LED3")
			(options
				(clearance outline)
				(anchor circle)
			)
			(primitives
				(gr_poly
					(pts
						(arc
							(start -0.1778 0.2794)
							(mid -0.249642 0.249642)
							(end -0.2794 0.1778)
						)
						(arc
							(start -0.2794 -0.1778)
							(mid -0.249642 -0.249642)
							(end -0.1778 -0.2794)
						)
						(arc
							(start 0.1778 -0.2794)
							(mid 0.249642 -0.249642)
							(end 0.2794 -0.1778)
						)
						(arc
							(start 0.2794 0.1778)
							(mid 0.249642 0.249642)
							(end 0.1778 0.2794)
						)
					)
					(width 0)
					(fill yes)
				)
			)
		)
		(pad "2" smd custom
			(at 0 0.4445 180)
			(size 0.1397 0.1397)
			(layers "B.Cu" "B.Mask" "B.Paste")
			(net "P3V3_STBY")
			(options
				(clearance outline)
				(anchor circle)
			)
			(primitives
				(gr_poly
					(pts
						(arc
							(start -0.1778 0.2794)
							(mid -0.249642 0.249642)
							(end -0.2794 0.1778)
						)
						(arc
							(start -0.2794 -0.1778)
							(mid -0.249642 -0.249642)
							(end -0.1778 -0.2794)
						)
						(arc
							(start 0.1778 -0.2794)
							(mid 0.249642 -0.249642)
							(end 0.2794 -0.1778)
						)
						(arc
							(start 0.2794 0.1778)
							(mid 0.249642 0.249642)
							(end 0.1778 0.2794)
						)
					)
					(width 0)
					(fill yes)
				)
			)
		)
	)
	(footprint ""
		(layer "B.Cu")
		(at 104.902 -239.395)
		(property "Reference" "SR946"
			(at 0 0 0)
			(layer "B.SilkS")
			(hide yes)
			(effects
				(font
					(size 1.27 1.27)
				)
				(justify mirror)
			)
		)
		(property "Value" "4K7R2F-GP"
			(at -0.064008 -3.993896 0)
			(unlocked yes)
			(layer "B.Fab")
			(hide yes)
			(effects
				(font
					(size 1.016 1.016)
					(thickness 0.1524)
				)
				(justify mirror)
			)
		)
		(property "Device Type" "R402H16"
			(at -0.064008 -5.517896 0)
			(unlocked yes)
			(layer "B.Fab")
			(hide yes)
			(effects
				(font
					(size 1.016 1.016)
					(thickness 0.1524)
				)
				(justify mirror)
			)
		)
		(duplicate_pad_numbers_are_jumpers no)
		(fp_line
			(start -0.508 -0.9398)
			(end 0.508 -0.9398)
			(stroke
				(width 0.1524)
				(type default)
			)
			(layer "B.SilkS")
		)
		(fp_line
			(start 0.508 -0.9398)
			(end 0.508 0.9398)
			(stroke
				(width 0.1524)
				(type default)
			)
			(layer "B.SilkS")
		)
		(fp_rect
			(start 0.508 0.9398)
			(end -0.508 -0.9398)
			(stroke
				(width 0)
				(type default)
			)
			(fill no)
			(layer "B.CrtYd")
		)
		(fp_rect
			(start 0.508 0.9398)
			(end -0.508 -0.9398)
			(stroke
				(width 0)
				(type default)
			)
			(fill no)
			(layer "B.Fab")
		)
		(pad "1" smd custom
			(at 0 -0.4445 180)
			(size 0.1397 0.1397)
			(layers "B.Cu" "B.Mask" "B.Paste")
			(net "SAS_FAULT_LED5")
			(options
				(clearance outline)
				(anchor circle)
			)
			(primitives
				(gr_poly
					(pts
						(arc
							(start -0.1778 0.2794)
							(mid -0.249642 0.249642)
							(end -0.2794 0.1778)
						)
						(arc
							(start -0.2794 -0.1778)
							(mid -0.249642 -0.249642)
							(end -0.1778 -0.2794)
						)
						(arc
							(start 0.1778 -0.2794)
							(mid 0.249642 -0.249642)
							(end 0.2794 -0.1778)
						)
						(arc
							(start 0.2794 0.1778)
							(mid 0.249642 0.249642)
							(end 0.1778 0.2794)
						)
					)
					(width 0)
					(fill yes)
				)
			)
		)
		(pad "2" smd custom
			(at 0 0.4445 180)
			(size 0.1397 0.1397)
			(layers "B.Cu" "B.Mask" "B.Paste")
			(net "P3V3_STBY")
			(options
				(clearance outline)
				(anchor circle)
			)
			(primitives
				(gr_poly
					(pts
						(arc
							(start -0.1778 0.2794)
							(mid -0.249642 0.249642)
							(end -0.2794 0.1778)
						)
						(arc
							(start -0.2794 -0.1778)
							(mid -0.249642 -0.249642)
							(end -0.1778 -0.2794)
						)
						(arc
							(start 0.1778 -0.2794)
							(mid 0.249642 -0.249642)
							(end 0.2794 -0.1778)
						)
						(arc
							(start 0.2794 0.1778)
							(mid 0.249642 0.249642)
							(end 0.1778 0.2794)
						)
					)
					(width 0)
					(fill yes)
				)
			)
		)
	)
	(footprint ""
		(layer "B.Cu")
		(at 139.33297 -87.249)
		(property "Reference" "R597"
			(at 0 0 0)
			(layer "B.SilkS")
			(hide yes)
			(effects
				(font
					(size 1.27 1.27)
				)
				(justify mirror)
			)
		)
		(property "Value" "4K7R2F-GP"
			(at -0.064008 -3.993896 0)
			(unlocked yes)
			(layer "B.Fab")
			(hide yes)
			(effects
				(font
					(size 1.016 1.016)
					(thickness 0.1524)
				)
				(justify mirror)
			)
		)
		(property "Device Type" "R402H16"
			(at -0.064008 -5.517896 0)
			(unlocked yes)
			(layer "B.Fab")
			(hide yes)
			(effects
				(font
					(size 1.016 1.016)
					(thickness 0.1524)
				)
				(justify mirror)
			)
		)
		(duplicate_pad_numbers_are_jumpers no)
		(fp_line
			(start -0.508 -0.9398)
			(end 0.508 -0.9398)
			(stroke
				(width 0.1524)
				(type default)
			)
			(layer "B.SilkS")
		)
		(fp_line
			(start 0.508 -0.9398)
			(end 0.508 0.9398)
			(stroke
				(width 0.1524)
				(type default)
			)
			(layer "B.SilkS")
		)
		(fp_rect
			(start 0.508 0.9398)
			(end -0.508 -0.9398)
			(stroke
				(width 0)
				(type default)
			)
			(fill no)
			(layer "B.CrtYd")
		)
		(fp_rect
			(start 0.508 0.9398)
			(end -0.508 -0.9398)
			(stroke
				(width 0)
				(type default)
			)
			(fill no)
			(layer "B.Fab")
		)
		(pad "1" smd custom
			(at 0 -0.4445 180)
			(size 0.1397 0.1397)
			(layers "B.Cu" "B.Mask" "B.Paste")
			(net "P3V3_STBY")
			(options
				(clearance outline)
				(anchor circle)
			)
			(primitives
				(gr_poly
					(pts
						(arc
							(start -0.1778 0.2794)
							(mid -0.249642 0.249642)
							(end -0.2794 0.1778)
						)
						(arc
							(start -0.2794 -0.1778)
							(mid -0.249642 -0.249642)
							(end -0.1778 -0.2794)
						)
						(arc
							(start 0.1778 -0.2794)
							(mid 0.249642 -0.249642)
							(end 0.2794 -0.1778)
						)
						(arc
							(start 0.2794 0.1778)
							(mid 0.249642 0.249642)
							(end 0.1778 0.2794)
						)
					)
					(width 0)
					(fill yes)
				)
			)
		)
		(pad "2" smd custom
			(at 0 0.4445 180)
			(size 0.1397 0.1397)
			(layers "B.Cu" "B.Mask" "B.Paste")
			(net "TEMP_3_A2")
			(options
				(clearance outline)
				(anchor circle)
			)
			(primitives
				(gr_poly
					(pts
						(arc
							(start -0.1778 0.2794)
							(mid -0.249642 0.249642)
							(end -0.2794 0.1778)
						)
						(arc
							(start -0.2794 -0.1778)
							(mid -0.249642 -0.249642)
							(end -0.1778 -0.2794)
						)
						(arc
							(start 0.1778 -0.2794)
							(mid 0.249642 -0.249642)
							(end 0.2794 -0.1778)
						)
						(arc
							(start 0.2794 0.1778)
							(mid 0.249642 0.249642)
							(end 0.1778 0.2794)
						)
					)
					(width 0)
					(fill yes)
				)
			)
		)
	)
	(footprint ""
		(layer "B.Cu")
		(at 158.42996 -105.003854 90)
		(property "Reference" "SC1241"
			(at 0 0 90)
			(layer "B.SilkS")
			(hide yes)
			(effects
				(font
					(size 1.27 1.27)
				)
				(justify mirror)
			)
		)
		(property "Value" "SCD1U6D3V1KX-GP"
			(at 2.8321 -1.7399 90)
			(unlocked yes)
			(layer "B.Fab")
			(hide yes)
			(effects
				(font
					(size 1.016 1.016)
					(thickness 0.1524)
				)
				(justify mirror)
			)
		)
		(property "Device Type" "C0201H13"
			(at 2.8321 -3.2639 90)
			(unlocked yes)
			(layer "B.Fab")
			(hide yes)
			(effects
				(font
					(size 1.016 1.016)
					(thickness 0.1524)
				)
				(justify mirror)
			)
		)
		(duplicate_pad_numbers_are_jumpers no)
		(fp_rect
			(start 0.2794 0.6477)
			(end -0.2794 -0.6477)
			(stroke
				(width 0)
				(type default)
			)
			(fill no)
			(layer "B.CrtYd")
		)
		(fp_rect
			(start 0.2794 0.6477)
			(end -0.2794 -0.6477)
			(stroke
				(width 0)
				(type default)
			)
			(fill no)
			(layer "B.Fab")
		)
		(pad "1" smd custom
			(at 0 -0.2794 270)
			(size 0.0762 0.0762)
			(layers "B.Cu" "B.Mask" "B.Paste")
			(net "P0V9_E")
			(options
				(clearance outline)
				(anchor circle)
			)
			(primitives
				(gr_poly
					(pts
						(arc
							(start 0.1524 0.127)
							(mid 0.137521 0.162921)
							(end 0.1016 0.1778)
						)
						(arc
							(start -0.1016 0.1778)
							(mid -0.137521 0.162921)
							(end -0.1524 0.127)
						)
						(arc
							(start -0.1524 -0.127)
							(mid -0.137521 -0.162921)
							(end -0.1016 -0.1778)
						)
						(arc
							(start 0.1016 -0.1778)
							(mid 0.137521 -0.162921)
							(end 0.1524 -0.127)
						)
					)
					(width 0)
					(fill yes)
				)
			)
		)
		(pad "2" smd custom
			(at 0 0.2794 270)
			(size 0.0762 0.0762)
			(layers "B.Cu" "B.Mask" "B.Paste")
			(net "GND")
			(options
				(clearance outline)
				(anchor circle)
			)
			(primitives
				(gr_poly
					(pts
						(arc
							(start 0.1524 0.127)
							(mid 0.137521 0.162921)
							(end 0.1016 0.1778)
						)
						(arc
							(start -0.1016 0.1778)
							(mid -0.137521 0.162921)
							(end -0.1524 0.127)
						)
						(arc
							(start -0.1524 -0.127)
							(mid -0.137521 -0.162921)
							(end -0.1016 -0.1778)
						)
						(arc
							(start 0.1016 -0.1778)
							(mid 0.137521 -0.162921)
							(end 0.1524 -0.127)
						)
					)
					(width 0)
					(fill yes)
				)
			)
		)
	)
	(footprint ""
		(layer "B.Cu")
		(at 104.65816 -31.623)
		(property "Reference" "SC876"
			(at 0 0 0)
			(layer "B.SilkS")
			(hide yes)
			(effects
				(font
					(size 1.27 1.27)
				)
				(justify mirror)
			)
		)
		(property "Value" "SCD22U6D3V1MX-1-GP"
			(at 2.8321 -1.7399 0)
			(unlocked yes)
			(layer "B.Fab")
			(hide yes)
			(effects
				(font
					(size 1.016 1.016)
					(thickness 0.1524)
				)
				(justify mirror)
			)
		)
		(property "Device Type" "C0201H13"
			(at 2.8321 -3.2639 0)
			(unlocked yes)
			(layer "B.Fab")
			(hide yes)
			(effects
				(font
					(size 1.016 1.016)
					(thickness 0.1524)
				)
				(justify mirror)
			)
		)
		(duplicate_pad_numbers_are_jumpers no)
		(fp_rect
			(start 0.2794 0.6477)
			(end -0.2794 -0.6477)
			(stroke
				(width 0)
				(type default)
			)
			(fill no)
			(layer "B.CrtYd")
		)
		(fp_rect
			(start 0.2794 0.6477)
			(end -0.2794 -0.6477)
			(stroke
				(width 0)
				(type default)
			)
			(fill no)
			(layer "B.Fab")
		)
		(pad "1" smd custom
			(at 0 -0.2794 180)
			(size 0.0762 0.0762)
			(layers "B.Cu" "B.Mask" "B.Paste")
			(net "PCIE_SAS_C_CPU_RX_N7")
			(options
				(clearance outline)
				(anchor circle)
			)
			(primitives
				(gr_poly
					(pts
						(arc
							(start 0.1524 0.127)
							(mid 0.137521 0.162921)
							(end 0.1016 0.1778)
						)
						(arc
							(start -0.1016 0.1778)
							(mid -0.137521 0.162921)
							(end -0.1524 0.127)
						)
						(arc
							(start -0.1524 -0.127)
							(mid -0.137521 -0.162921)
							(end -0.1016 -0.1778)
						)
						(arc
							(start 0.1016 -0.1778)
							(mid 0.137521 -0.162921)
							(end 0.1524 -0.127)
						)
					)
					(width 0)
					(fill yes)
				)
			)
		)
		(pad "2" smd custom
			(at 0 0.2794 180)
			(size 0.0762 0.0762)
			(layers "B.Cu" "B.Mask" "B.Paste")
			(net "PCIE_SAS_CPU_RX_N7")
			(options
				(clearance outline)
				(anchor circle)
			)
			(primitives
				(gr_poly
					(pts
						(arc
							(start 0.1524 0.127)
							(mid 0.137521 0.162921)
							(end 0.1016 0.1778)
						)
						(arc
							(start -0.1016 0.1778)
							(mid -0.137521 0.162921)
							(end -0.1524 0.127)
						)
						(arc
							(start -0.1524 -0.127)
							(mid -0.137521 -0.162921)
							(end -0.1016 -0.1778)
						)
						(arc
							(start 0.1016 -0.1778)
							(mid 0.137521 -0.162921)
							(end 0.1524 -0.127)
						)
					)
					(width 0)
					(fill yes)
				)
			)
		)
	)
	(footprint ""
		(layer "B.Cu")
		(at 119.90197 -86.741)
		(property "Reference" "STP103"
			(at 0 0 0)
			(layer "B.SilkS")
			(hide yes)
			(effects
				(font
					(size 1.27 1.27)
				)
				(justify mirror)
			)
		)
		(property "Value" "TPAD28"
			(at -0.0127 -1.8034 0)
			(unlocked yes)
			(layer "B.Fab")
			(hide yes)
			(effects
				(font
					(size 1.016 1.016)
					(thickness 0.1524)
				)
				(justify mirror)
			)
		)
		(property "Device Type" "TPAD28"
			(at -0.0127 -3.3274 0)
			(unlocked yes)
			(layer "B.Fab")
			(hide yes)
			(effects
				(font
					(size 1.016 1.016)
					(thickness 0.1524)
				)
				(justify mirror)
			)
		)
		(duplicate_pad_numbers_are_jumpers no)
		(fp_poly
			(pts
				(arc
					(start 0.3556 0)
					(mid -0.3556 0)
					(end 0.3556 0)
				)
			)
			(stroke
				(width 0)
				(type default)
			)
			(fill no)
			(layer "B.CrtYd")
		)
		(fp_poly
			(pts
				(arc
					(start 0.6096 0)
					(mid -0.6096 0)
					(end 0.6096 0)
				)
			)
			(stroke
				(width 0)
				(type default)
			)
			(fill no)
			(layer "B.Fab")
		)
		(pad "1" smd circle
			(at 0 0 180)
			(size 0.7112 0.7112)
			(layers "B.Cu" "B.Mask" "B.Paste")
			(net "TEST_MUX_36")
		)
	)
)
